G04 ================== begin FILE IDENTIFICATION RECORD ==================*
G04 Layout Name:  17301-sa.brd*
G04 Film Name:    TMASK*
G04 File Format:  Gerber RS274X*
G04 File Origin:  Cadence Allegro 16.6-2015-S079*
G04 Origin Date:  Thu Jun 22 17:49:53 2017*
G04 *
G04 Layer:  VIA CLASS/SOLDERMASK_TOP*
G04 Layer:  PIN/SOLDERMASK_TOP*
G04 Layer:  PACKAGE GEOMETRY/SOLDERMASK_TOP*
G04 Layer:  DRAWING FORMAT/LAYER_SOLDER_T*
G04 Layer:  BOARD GEOMETRY/SOLDERMASK_TOP*
G04 Layer:  DRAWING FORMAT/LAYER_PCB_STORY*
G04 *
G04 Offset:    (0.00 0.00)*
G04 Mirror:    No*
G04 Mode:      Positive*
G04 Rotation:  0*
G04 FullContactRelief:  No*
G04 UndefLineWidth:     6.00*
G04 ================== end FILE IDENTIFICATION RECORD ====================*
%FSLAX35Y35*MOIN*%
%IR0*IPPOS*OFA0.00000B0.00000*MIA0B0*SFA1.00000B1.00000*%
%AMMACRO21*
4,1,40,.013,.017,
-.013,.017,
-.013695,.016939,
-.014368,.016759,
-.015,.016464,
-.015571,.016064,
-.016064,.015571,
-.016464,.015,
-.016759,.014368,
-.016939,.013695,
-.017,.013,
-.017,-.013,
-.016939,-.013695,
-.016759,-.014368,
-.016464,-.015,
-.016064,-.015571,
-.015571,-.016064,
-.015,-.016464,
-.014368,-.016759,
-.013695,-.016939,
-.013,-.017,
.013,-.017,
.013695,-.016939,
.014368,-.016759,
.015,-.016464,
.015571,-.016064,
.016064,-.015571,
.016464,-.015,
.016759,-.014368,
.016939,-.013695,
.017,-.013,
.017,.013,
.016939,.013695,
.016759,.014368,
.016464,.015,
.016064,.015571,
.015571,.016064,
.015,.016464,
.014368,.016759,
.013695,.016939,
.013,.017,
0.0*
%
%ADD21MACRO21*%
%ADD39C,.05*%
%ADD17C,.014*%
%ADD16C,.034*%
%ADD40C,.071*%
%ADD26C,.053*%
%ADD12C,.08*%
%ADD30C,.028*%
%ADD34C,.048*%
%ADD15C,.093*%
%ADD10C,.086*%
%AMMACRO35*
4,1,40,.011,-.007,
.011,.007,
.010939,.007695,
.010759,.008368,
.010464,.009,
.010064,.009571,
.009571,.010064,
.009,.010464,
.008368,.010759,
.007695,.010939,
.007,.011,
-.007,.011,
-.007695,.010939,
-.008368,.010759,
-.009,.010464,
-.009571,.010064,
-.010064,.009571,
-.010464,.009,
-.010759,.008368,
-.010939,.007695,
-.011,.007,
-.011,-.007,
-.010939,-.007695,
-.010759,-.008368,
-.010464,-.009,
-.010064,-.009571,
-.009571,-.010064,
-.009,-.010464,
-.008368,-.010759,
-.007695,-.010939,
-.007,-.011,
.007,-.011,
.007695,-.010939,
.008368,-.010759,
.009,-.010464,
.009571,-.010064,
.010064,-.009571,
.010464,-.009,
.010759,-.008368,
.010939,-.007695,
.011,-.007,
0.0*
%
%ADD35MACRO35*%
%AMMACRO23*
4,1,40,-.012,.008,
-.012,-.008,
-.011939,-.008695,
-.011759,-.009368,
-.011464,-.01,
-.011064,-.010571,
-.010571,-.011064,
-.01,-.011464,
-.009368,-.011759,
-.008695,-.011939,
-.008,-.012,
.008,-.012,
.008695,-.011939,
.009368,-.011759,
.01,-.011464,
.010571,-.011064,
.011064,-.010571,
.011464,-.01,
.011759,-.009368,
.011939,-.008695,
.012,-.008,
.012,.008,
.011939,.008695,
.011759,.009368,
.011464,.01,
.011064,.010571,
.010571,.011064,
.01,.011464,
.009368,.011759,
.008695,.011939,
.008,.012,
-.008,.012,
-.008695,.011939,
-.009368,.011759,
-.01,.011464,
-.010571,.011064,
-.011064,.010571,
-.011464,.01,
-.011759,.009368,
-.011939,.008695,
-.012,.008,
0.0*
%
%ADD23MACRO23*%
%AMMACRO38*
4,1,40,.008,.012,
-.008,.012,
-.008695,.011939,
-.009368,.011759,
-.01,.011464,
-.010571,.011064,
-.011064,.010571,
-.011464,.01,
-.011759,.009368,
-.011939,.008695,
-.012,.008,
-.012,-.008,
-.011939,-.008695,
-.011759,-.009368,
-.011464,-.01,
-.011064,-.010571,
-.010571,-.011064,
-.01,-.011464,
-.009368,-.011759,
-.008695,-.011939,
-.008,-.012,
.008,-.012,
.008695,-.011939,
.009368,-.011759,
.01,-.011464,
.010571,-.011064,
.011064,-.010571,
.011464,-.01,
.011759,-.009368,
.011939,-.008695,
.012,-.008,
.012,.008,
.011939,.008695,
.011759,.009368,
.011464,.01,
.011064,.010571,
.010571,.011064,
.01,.011464,
.009368,.011759,
.008695,.011939,
.008,.012,
0.0*
%
%ADD38MACRO38*%
%AMMACRO36*
4,1,40,.011,-.007,
.011,.007,
.010939,.007695,
.010759,.008368,
.010464,.009,
.010064,.009571,
.009571,.010064,
.009,.010464,
.008368,.010759,
.007695,.010939,
.007,.011,
-.007,.011,
-.007695,.010939,
-.008368,.010759,
-.009,.010464,
-.009571,.010064,
-.010064,.009571,
-.010464,.009,
-.010759,.008368,
-.010939,.007695,
-.011,.007,
-.011,-.007,
-.010939,-.007695,
-.010759,-.008368,
-.010464,-.009,
-.010064,-.009571,
-.009571,-.010064,
-.009,-.010464,
-.008368,-.010759,
-.007695,-.010939,
-.007,-.011,
.007,-.011,
.007695,-.010939,
.008368,-.010759,
.009,-.010464,
.009571,-.010064,
.010064,-.009571,
.010464,-.009,
.010759,-.008368,
.010939,-.007695,
.011,-.007,
0.0*
%
%ADD36MACRO36*%
%AMMACRO22*
4,1,40,-.012,.008,
-.012,-.008,
-.011939,-.008695,
-.011759,-.009368,
-.011464,-.01,
-.011064,-.010571,
-.010571,-.011064,
-.01,-.011464,
-.009368,-.011759,
-.008695,-.011939,
-.008,-.012,
.008,-.012,
.008695,-.011939,
.009368,-.011759,
.01,-.011464,
.010571,-.011064,
.011064,-.010571,
.011464,-.01,
.011759,-.009368,
.011939,-.008695,
.012,-.008,
.012,.008,
.011939,.008695,
.011759,.009368,
.011464,.01,
.011064,.010571,
.010571,.011064,
.01,.011464,
.009368,.011759,
.008695,.011939,
.008,.012,
-.008,.012,
-.008695,.011939,
-.009368,.011759,
-.01,.011464,
-.010571,.011064,
-.011064,.010571,
-.011464,.01,
-.011759,.009368,
-.011939,.008695,
-.012,.008,
0.0*
%
%ADD22MACRO22*%
%AMMACRO37*
4,1,40,.008,.012,
-.008,.012,
-.008695,.011939,
-.009368,.011759,
-.01,.011464,
-.010571,.011064,
-.011064,.010571,
-.011464,.01,
-.011759,.009368,
-.011939,.008695,
-.012,.008,
-.012,-.008,
-.011939,-.008695,
-.011759,-.009368,
-.011464,-.01,
-.011064,-.010571,
-.010571,-.011064,
-.01,-.011464,
-.009368,-.011759,
-.008695,-.011939,
-.008,-.012,
.008,-.012,
.008695,-.011939,
.009368,-.011759,
.01,-.011464,
.010571,-.011064,
.011064,-.010571,
.011464,-.01,
.011759,-.009368,
.011939,-.008695,
.012,-.008,
.012,.008,
.011939,.008695,
.011759,.009368,
.011464,.01,
.011064,.010571,
.010571,.011064,
.01,.011464,
.009368,.011759,
.008695,.011939,
.008,.012,
0.0*
%
%ADD37MACRO37*%
%ADD18O,.024X.032*%
%ADD29R,.05X.065*%
%ADD20R,.045X.055*%
%ADD11C,.217*%
%ADD31O,.086X.048*%
%AMMACRO32*
4,1,40,-.007,-.011,
.007,-.011,
.007695,-.010939,
.008368,-.010759,
.009,-.010464,
.009571,-.010064,
.010064,-.009571,
.010464,-.009,
.010759,-.008368,
.010939,-.007695,
.011,-.007,
.011,.007,
.010939,.007695,
.010759,.008368,
.010464,.009,
.010064,.009571,
.009571,.010064,
.009,.010464,
.008368,.010759,
.007695,.010939,
.007,.011,
-.007,.011,
-.007695,.010939,
-.008368,.010759,
-.009,.010464,
-.009571,.010064,
-.010064,.009571,
-.010464,.009,
-.010759,.008368,
-.010939,.007695,
-.011,.007,
-.011,-.007,
-.010939,-.007695,
-.010759,-.008368,
-.010464,-.009,
-.010064,-.009571,
-.009571,-.010064,
-.009,-.010464,
-.008368,-.010759,
-.007695,-.010939,
-.007,-.011,
0.0*
%
%ADD32MACRO32*%
%AMMACRO25*
4,1,40,-.008,-.012,
.008,-.012,
.008695,-.011939,
.009368,-.011759,
.01,-.011464,
.010571,-.011064,
.011064,-.010571,
.011464,-.01,
.011759,-.009368,
.011939,-.008695,
.012,-.008,
.012,.008,
.011939,.008695,
.011759,.009368,
.011464,.01,
.011064,.010571,
.010571,.011064,
.01,.011464,
.009368,.011759,
.008695,.011939,
.008,.012,
-.008,.012,
-.008695,.011939,
-.009368,.011759,
-.01,.011464,
-.010571,.011064,
-.011064,.010571,
-.011464,.01,
-.011759,.009368,
-.011939,.008695,
-.012,.008,
-.012,-.008,
-.011939,-.008695,
-.011759,-.009368,
-.011464,-.01,
-.011064,-.010571,
-.010571,-.011064,
-.01,-.011464,
-.009368,-.011759,
-.008695,-.011939,
-.008,-.012,
0.0*
%
%ADD25MACRO25*%
%AMMACRO14*
4,1,40,.012,-.008,
.012,.008,
.011939,.008695,
.011759,.009368,
.011464,.01,
.011064,.010571,
.010571,.011064,
.01,.011464,
.009368,.011759,
.008695,.011939,
.008,.012,
-.008,.012,
-.008695,.011939,
-.009368,.011759,
-.01,.011464,
-.010571,.011064,
-.011064,.010571,
-.011464,.01,
-.011759,.009368,
-.011939,.008695,
-.012,.008,
-.012,-.008,
-.011939,-.008695,
-.011759,-.009368,
-.011464,-.01,
-.011064,-.010571,
-.010571,-.011064,
-.01,-.011464,
-.009368,-.011759,
-.008695,-.011939,
-.008,-.012,
.008,-.012,
.008695,-.011939,
.009368,-.011759,
.01,-.011464,
.010571,-.011064,
.011064,-.010571,
.011464,-.01,
.011759,-.009368,
.011939,-.008695,
.012,-.008,
0.0*
%
%ADD14MACRO14*%
%AMMACRO27*
4,1,40,-.011,.007,
-.011,-.007,
-.010939,-.007695,
-.010759,-.008368,
-.010464,-.009,
-.010064,-.009571,
-.009571,-.010064,
-.009,-.010464,
-.008368,-.010759,
-.007695,-.010939,
-.007,-.011,
.007,-.011,
.007695,-.010939,
.008368,-.010759,
.009,-.010464,
.009571,-.010064,
.010064,-.009571,
.010464,-.009,
.010759,-.008368,
.010939,-.007695,
.011,-.007,
.011,.007,
.010939,.007695,
.010759,.008368,
.010464,.009,
.010064,.009571,
.009571,.010064,
.009,.010464,
.008368,.010759,
.007695,.010939,
.007,.011,
-.007,.011,
-.007695,.010939,
-.008368,.010759,
-.009,.010464,
-.009571,.010064,
-.010064,.009571,
-.010464,.009,
-.010759,.008368,
-.010939,.007695,
-.011,.007,
0.0*
%
%ADD27MACRO27*%
%AMMACRO19*
4,1,40,.013,.017,
-.013,.017,
-.013695,.016939,
-.014368,.016759,
-.015,.016464,
-.015571,.016064,
-.016064,.015571,
-.016464,.015,
-.016759,.014368,
-.016939,.013695,
-.017,.013,
-.017,-.013,
-.016939,-.013695,
-.016759,-.014368,
-.016464,-.015,
-.016064,-.015571,
-.015571,-.016064,
-.015,-.016464,
-.014368,-.016759,
-.013695,-.016939,
-.013,-.017,
.013,-.017,
.013695,-.016939,
.014368,-.016759,
.015,-.016464,
.015571,-.016064,
.016064,-.015571,
.016464,-.015,
.016759,-.014368,
.016939,-.013695,
.017,-.013,
.017,.013,
.016939,.013695,
.016759,.014368,
.016464,.015,
.016064,.015571,
.015571,.016064,
.015,.016464,
.014368,.016759,
.013695,.016939,
.013,.017,
0.0*
%
%ADD19MACRO19*%
%AMMACRO33*
4,1,40,-.007,-.011,
.007,-.011,
.007695,-.010939,
.008368,-.010759,
.009,-.010464,
.009571,-.010064,
.010064,-.009571,
.010464,-.009,
.010759,-.008368,
.010939,-.007695,
.011,-.007,
.011,.007,
.010939,.007695,
.010759,.008368,
.010464,.009,
.010064,.009571,
.009571,.010064,
.009,.010464,
.008368,.010759,
.007695,.010939,
.007,.011,
-.007,.011,
-.007695,.010939,
-.008368,.010759,
-.009,.010464,
-.009571,.010064,
-.010064,.009571,
-.010464,.009,
-.010759,.008368,
-.010939,.007695,
-.011,.007,
-.011,-.007,
-.010939,-.007695,
-.010759,-.008368,
-.010464,-.009,
-.010064,-.009571,
-.009571,-.010064,
-.009,-.010464,
-.008368,-.010759,
-.007695,-.010939,
-.007,-.011,
0.0*
%
%ADD33MACRO33*%
%AMMACRO24*
4,1,40,-.008,-.012,
.008,-.012,
.008695,-.011939,
.009368,-.011759,
.01,-.011464,
.010571,-.011064,
.011064,-.010571,
.011464,-.01,
.011759,-.009368,
.011939,-.008695,
.012,-.008,
.012,.008,
.011939,.008695,
.011759,.009368,
.011464,.01,
.011064,.010571,
.010571,.011064,
.01,.011464,
.009368,.011759,
.008695,.011939,
.008,.012,
-.008,.012,
-.008695,.011939,
-.009368,.011759,
-.01,.011464,
-.010571,.011064,
-.011064,.010571,
-.011464,.01,
-.011759,.009368,
-.011939,.008695,
-.012,.008,
-.012,-.008,
-.011939,-.008695,
-.011759,-.009368,
-.011464,-.01,
-.011064,-.010571,
-.010571,-.011064,
-.01,-.011464,
-.009368,-.011759,
-.008695,-.011939,
-.008,-.012,
0.0*
%
%ADD24MACRO24*%
%AMMACRO13*
4,1,40,.012,-.008,
.012,.008,
.011939,.008695,
.011759,.009368,
.011464,.01,
.011064,.010571,
.010571,.011064,
.01,.011464,
.009368,.011759,
.008695,.011939,
.008,.012,
-.008,.012,
-.008695,.011939,
-.009368,.011759,
-.01,.011464,
-.010571,.011064,
-.011064,.010571,
-.011464,.01,
-.011759,.009368,
-.011939,.008695,
-.012,.008,
-.012,-.008,
-.011939,-.008695,
-.011759,-.009368,
-.011464,-.01,
-.011064,-.010571,
-.010571,-.011064,
-.01,-.011464,
-.009368,-.011759,
-.008695,-.011939,
-.008,-.012,
.008,-.012,
.008695,-.011939,
.009368,-.011759,
.01,-.011464,
.010571,-.011064,
.011064,-.010571,
.011464,-.01,
.011759,-.009368,
.011939,-.008695,
.012,-.008,
0.0*
%
%ADD13MACRO13*%
%AMMACRO28*
4,1,40,-.011,.007,
-.011,-.007,
-.010939,-.007695,
-.010759,-.008368,
-.010464,-.009,
-.010064,-.009571,
-.009571,-.010064,
-.009,-.010464,
-.008368,-.010759,
-.007695,-.010939,
-.007,-.011,
.007,-.011,
.007695,-.010939,
.008368,-.010759,
.009,-.010464,
.009571,-.010064,
.010064,-.009571,
.010464,-.009,
.010759,-.008368,
.010939,-.007695,
.011,-.007,
.011,.007,
.010939,.007695,
.010759,.008368,
.010464,.009,
.010064,.009571,
.009571,.010064,
.009,.010464,
.008368,.010759,
.007695,.010939,
.007,.011,
-.007,.011,
-.007695,.010939,
-.008368,.010759,
-.009,.010464,
-.009571,.010064,
-.010064,.009571,
-.010464,.009,
-.010759,.008368,
-.010939,.007695,
-.011,.007,
0.0*
%
%ADD28MACRO28*%
%ADD41C,.02*%
%ADD42C,.006*%
G75*
%LPD*%
G75*
G54D10*
X-14755Y415558D03*
X-12454Y45507D03*
X17715Y44095D03*
X29461Y718854D03*
X141466Y655356D03*
X395935Y76695D03*
X508569Y15093D03*
X525590Y240944D03*
X552795Y40157D03*
X554126Y315939D03*
Y685624D03*
G54D11*
X15748Y15827D03*
Y67008D03*
X303150Y13780D03*
Y242913D03*
X551181Y13780D03*
Y242913D03*
G54D20*
X198356Y33399D03*
X205956D03*
X194830Y76364D03*
X202430D03*
X266292Y48559D03*
X273892D03*
X309800Y192500D03*
X302200D03*
X322966Y199919D03*
X309800Y200500D03*
X302200D03*
X337012Y44327D03*
X344612D03*
X324686Y162130D03*
X332286D03*
X330566Y199919D03*
G54D30*
X267148Y39395D03*
X271238Y67208D03*
X322100Y26600D03*
X309250Y127439D03*
X322042Y147196D03*
X310500Y152000D03*
X321777Y191293D03*
X310500Y184328D03*
X340000Y14667D03*
X336921Y51884D03*
X351040Y34753D03*
X358900Y23928D03*
G54D12*
X20847Y701602D03*
X32739Y30456D03*
X514356Y57612D03*
G54D21*
X192500Y32100D03*
X188300Y75000D03*
X226520Y33897D03*
X222194Y74962D03*
X469635Y224263D03*
X494300Y158300D03*
X497446Y224052D03*
X517300Y158500D03*
G54D13*
X48300Y76000D03*
Y79500D03*
X225756Y38299D03*
X221430Y79364D03*
X296700Y164800D03*
X307800Y209500D03*
Y206000D03*
G54D31*
X295472Y65571D03*
Y108287D03*
X330590Y65571D03*
Y108287D03*
G54D22*
X200674Y38941D03*
X196830Y81864D03*
G54D40*
X484960Y86811D03*
X496771D03*
X508583D03*
X520394D03*
G54D41*
G01X-139981Y-146685D02*
G02I-12000J0D01*
G01X-145131D02*
G02I-6850J0D01*
G01X-135981D02*
X-167981D01*
G01X-135981Y-162685D02*
Y-242685D01*
G01D02*
X971619D01*
G01X-135981Y-198185D02*
X971619D01*
G01X-151981Y-162685D02*
Y-130685D01*
G01X-135981Y-162685D02*
X971619D01*
G01X184119D02*
Y-242685D01*
G01X321619Y-162685D02*
Y-242685D01*
G01X436619Y-162685D02*
Y-242685D01*
G01X604119Y-162685D02*
Y-242685D01*
G01X774119Y-162685D02*
Y-242685D01*
G01X971619Y-162685D02*
Y-242685D01*
G01X999619Y-146685D02*
G02I-12000J0D01*
G01X1003619D02*
X971619D01*
G01X994469D02*
G02I-6850J0D01*
G01X987619Y-162685D02*
Y-130685D01*
G54D14*
X44700Y76000D03*
Y79500D03*
X222156Y38299D03*
X217830Y79364D03*
X293100Y164800D03*
X304200Y209500D03*
Y206000D03*
G54D32*
X316700Y32000D03*
X308700D03*
X321200Y142000D03*
X309200Y133500D03*
X339700Y20000D03*
X328700Y142000D03*
X352200Y29500D03*
X360200D03*
G54D23*
X204274Y38941D03*
X200430Y81864D03*
G54D42*
G01X-116181Y-215185D02*
Y-232685D01*
G01X-121203Y-215185D02*
X-111159D01*
G01X-103048Y-232685D02*
Y-215185D01*
X-97808D01*
X-96061Y-216060D01*
X-94751Y-218102D01*
X-94314Y-220435D01*
X-94751Y-222768D01*
X-95843Y-224518D01*
X-97808Y-225394D01*
X-103048D01*
G01X-58878Y-216644D02*
X-60188Y-215768D01*
X-61716Y-215185D01*
X-63463D01*
X-65428Y-216060D01*
X-66956Y-217518D01*
X-68048Y-219269D01*
X-68921Y-222185D01*
X-69140Y-224810D01*
X-68703Y-227435D01*
X-68048Y-229185D01*
X-66738Y-230935D01*
X-65209Y-232102D01*
X-63681Y-232685D01*
X-62153D01*
X-60624Y-232102D01*
X-59314Y-231227D01*
X-58222Y-230061D01*
G01X-49893Y-232685D02*
Y-215185D01*
G01Y-223643D02*
X-48801Y-222185D01*
X-47709Y-221310D01*
X-45963Y-221019D01*
X-44653Y-221310D01*
X-43124Y-222477D01*
X-42469Y-224227D01*
Y-232685D01*
G01X-24751D02*
Y-221019D01*
G01Y-223060D02*
X-25624Y-221894D01*
X-26935Y-221310D01*
X-28463Y-221019D01*
X-29991Y-221602D01*
X-31301Y-222768D01*
X-32175Y-224518D01*
X-32611Y-226852D01*
X-32175Y-229185D01*
X-31301Y-230935D01*
X-29991Y-232102D01*
X-28463Y-232685D01*
X-26935Y-232393D01*
X-25624Y-231519D01*
X-24751Y-230352D01*
G01X-14893Y-232685D02*
Y-221019D01*
G01Y-223935D02*
X-14019Y-222477D01*
X-12709Y-221310D01*
X-10963Y-221019D01*
X-9435Y-221310D01*
X-8124Y-222477D01*
X-7469Y-224518D01*
Y-232685D01*
G01X2607D02*
Y-221019D01*
G01Y-223935D02*
X3481Y-222477D01*
X4791Y-221310D01*
X6537Y-221019D01*
X8065Y-221310D01*
X9376Y-222477D01*
X10031Y-224518D01*
Y-232685D01*
G01X20544Y-224810D02*
X27531D01*
X26876Y-222768D01*
X25784Y-221602D01*
X24256Y-221019D01*
X22727Y-221310D01*
X21417Y-222185D01*
X20544Y-224227D01*
X20107Y-225977D01*
Y-227727D01*
X20544Y-229477D01*
X21636Y-231227D01*
X22946Y-232393D01*
X24474Y-232685D01*
X26002Y-232102D01*
X27531Y-230352D01*
G01X41319Y-232685D02*
Y-215185D01*
G01X71734Y-232685D02*
Y-215185D01*
G01X80904D02*
Y-232685D01*
G01Y-223935D02*
X71734D01*
G01X89016Y-232685D02*
Y-215185D01*
X93382D01*
X95129Y-216060D01*
X96439Y-217227D01*
X97531Y-218976D01*
X98404Y-221019D01*
X98622Y-223935D01*
X98404Y-226852D01*
X97531Y-228894D01*
X96439Y-230644D01*
X95129Y-231810D01*
X93382Y-232685D01*
X89016D01*
G01X106516D02*
Y-215185D01*
X110882D01*
X112629Y-216060D01*
X113939Y-217227D01*
X115031Y-218976D01*
X115904Y-221019D01*
X116122Y-223935D01*
X115904Y-226852D01*
X115031Y-228894D01*
X113939Y-230644D01*
X112629Y-231810D01*
X110882Y-232685D01*
X106516D01*
G01X148065Y-223352D02*
X148939Y-222477D01*
X149594Y-221019D01*
X150031Y-218976D01*
X149594Y-217227D01*
X148721Y-216060D01*
X147192Y-215185D01*
X141297D01*
Y-232685D01*
X148502D01*
X150031Y-231519D01*
X150904Y-229768D01*
X151341Y-227727D01*
X150904Y-225685D01*
X149594Y-223935D01*
X148065Y-223352D01*
X141297D01*
G01X159452Y-232685D02*
Y-215185D01*
X164692D01*
X166439Y-216060D01*
X167749Y-218102D01*
X168186Y-220435D01*
X167749Y-222768D01*
X166657Y-224518D01*
X164692Y-225394D01*
X159452D01*
G01X-16858Y-187685D02*
Y-170185D01*
X-11181Y-184768D01*
X-5504Y-170185D01*
Y-187685D01*
G01X6319D02*
X5009Y-187393D01*
X3699Y-186227D01*
X2825Y-184185D01*
X2389Y-181852D01*
X2825Y-179518D01*
X3699Y-177477D01*
X5009Y-176310D01*
X6319Y-176019D01*
X7629Y-176310D01*
X8939Y-177477D01*
X9812Y-179518D01*
X10031Y-181852D01*
X9812Y-184185D01*
X8939Y-186227D01*
X7629Y-187393D01*
X6319Y-187685D01*
G01X27749Y-170185D02*
Y-187685D01*
G01Y-185061D02*
X26876Y-186519D01*
X25565Y-187393D01*
X24037Y-187685D01*
X22291Y-187102D01*
X20981Y-185644D01*
X20107Y-183894D01*
X19889Y-181852D01*
X20107Y-179810D01*
X20981Y-178060D01*
X22291Y-176602D01*
X24037Y-176019D01*
X25565Y-176310D01*
X26657Y-176894D01*
X27749Y-178060D01*
G01X38044Y-179810D02*
X45031D01*
X44376Y-177768D01*
X43284Y-176602D01*
X41756Y-176019D01*
X40227Y-176310D01*
X38917Y-177185D01*
X38044Y-179227D01*
X37607Y-180977D01*
Y-182727D01*
X38044Y-184477D01*
X39136Y-186227D01*
X40446Y-187393D01*
X41974Y-187685D01*
X43502Y-187102D01*
X45031Y-185352D01*
G01X58819Y-187685D02*
Y-170185D01*
G01X204702Y-187685D02*
Y-170185D01*
X209942D01*
X211689Y-171060D01*
X212999Y-173102D01*
X213436Y-175435D01*
X212999Y-177768D01*
X211907Y-179518D01*
X209942Y-180394D01*
X204702D01*
G01X231372Y-171644D02*
X230062Y-170768D01*
X228534Y-170185D01*
X226787D01*
X224822Y-171060D01*
X223294Y-172518D01*
X222202Y-174269D01*
X221329Y-177185D01*
X221110Y-179810D01*
X221547Y-182435D01*
X222202Y-184185D01*
X223512Y-185935D01*
X225041Y-187102D01*
X226569Y-187685D01*
X228097D01*
X229626Y-187102D01*
X230936Y-186227D01*
X232028Y-185061D01*
G01X245815Y-178352D02*
X246689Y-177477D01*
X247344Y-176019D01*
X247781Y-173976D01*
X247344Y-172227D01*
X246471Y-171060D01*
X244942Y-170185D01*
X239047D01*
Y-187685D01*
X246252D01*
X247781Y-186519D01*
X248654Y-184768D01*
X249091Y-182727D01*
X248654Y-180685D01*
X247344Y-178935D01*
X245815Y-178352D01*
X239047D01*
G01X255019Y-193518D02*
X268119D01*
G01X274047Y-187685D02*
Y-170185D01*
X284091Y-187685D01*
Y-170185D01*
G01X296569Y-187685D02*
X294822Y-187393D01*
X293294Y-186227D01*
X291984Y-184477D01*
X291110Y-182435D01*
X290674Y-180102D01*
Y-177768D01*
X291110Y-175435D01*
X291984Y-173393D01*
X293294Y-171644D01*
X294822Y-170477D01*
X296569Y-170185D01*
X298315Y-170477D01*
X299844Y-171644D01*
X301154Y-173393D01*
X302028Y-175435D01*
X302464Y-177768D01*
Y-180102D01*
X302028Y-182435D01*
X301154Y-184477D01*
X299844Y-186227D01*
X298315Y-187393D01*
X296569Y-187685D01*
G01X217819Y-232685D02*
Y-215185D01*
X215199Y-218685D01*
G01Y-232685D02*
X220439D01*
G01X234882D02*
X235319Y-228894D01*
X235974Y-225685D01*
X236847Y-222768D01*
X237939Y-219560D01*
X239686Y-215185D01*
X230952D01*
G01X248016Y-229185D02*
X249325Y-231227D01*
X251072Y-232393D01*
X253037Y-232685D01*
X254784Y-232393D01*
X256531Y-230935D01*
X257622Y-229185D01*
X257841Y-227435D01*
X257404Y-225394D01*
X255876Y-223935D01*
X254347Y-223352D01*
X252382D01*
G01X254347D02*
X255657Y-222477D01*
X256749Y-221019D01*
X257186Y-219269D01*
X256749Y-217518D01*
X255657Y-216060D01*
X253692Y-215185D01*
X251727Y-215477D01*
X249762Y-216644D01*
G01X270319Y-215185D02*
X268572Y-215768D01*
X267262Y-217227D01*
X266389Y-218976D01*
X265734Y-221310D01*
X265516Y-223935D01*
X265734Y-226560D01*
X266389Y-228894D01*
X267262Y-230644D01*
X268572Y-232102D01*
X270319Y-232685D01*
X272065Y-232102D01*
X273376Y-230644D01*
X274249Y-228894D01*
X274904Y-226560D01*
X275122Y-223935D01*
X274904Y-221310D01*
X274249Y-218976D01*
X273376Y-217227D01*
X272065Y-215768D01*
X270319Y-215185D01*
G01X287819Y-232685D02*
Y-215185D01*
X285199Y-218685D01*
G01Y-232685D02*
X290439D01*
G01X365784Y-230352D02*
X367531Y-231810D01*
X369496Y-232685D01*
X371242D01*
X372989Y-231810D01*
X374299Y-230352D01*
X374954Y-228310D01*
X374517Y-226269D01*
X373426Y-224518D01*
X371461Y-223352D01*
X368841Y-222768D01*
X367312Y-221602D01*
X366657Y-219560D01*
X367094Y-217518D01*
X368186Y-216060D01*
X369714Y-215185D01*
X371242D01*
X372771Y-215768D01*
X374081Y-217227D01*
G01X382410Y-232685D02*
X387869Y-215185D01*
X393328Y-232685D01*
G01X391362Y-226560D02*
X384375D01*
G01X347410Y-170185D02*
X352869Y-187685D01*
X358328Y-170185D01*
G01X374736Y-187685D02*
X366002D01*
Y-170185D01*
X374736D01*
G01X371242Y-178643D02*
X366002D01*
G01X383502Y-187685D02*
Y-170185D01*
X388961D01*
X390707Y-171060D01*
X391799Y-172227D01*
X392236Y-174560D01*
X391799Y-176894D01*
X390489Y-178352D01*
X388961Y-179227D01*
X383502D01*
G01X388961D02*
X392236Y-187685D01*
G01X405369Y-188268D02*
X404932Y-187977D01*
Y-187393D01*
X405369Y-187102D01*
X405806Y-187393D01*
Y-187977D01*
X405369Y-188268D01*
G01X485319Y-215185D02*
Y-232685D01*
G01X480297Y-215185D02*
X490341D01*
G01X497142Y-232685D02*
Y-215185D01*
X502819Y-229768D01*
X508496Y-215185D01*
Y-232685D01*
G01X514860D02*
X520319Y-215185D01*
X525778Y-232685D01*
G01X523812Y-226560D02*
X516825D01*
G01X533234Y-230352D02*
X534981Y-231810D01*
X536946Y-232685D01*
X538692D01*
X540439Y-231810D01*
X541749Y-230352D01*
X542404Y-228310D01*
X541967Y-226269D01*
X540876Y-224518D01*
X538911Y-223352D01*
X536291Y-222768D01*
X534762Y-221602D01*
X534107Y-219560D01*
X534544Y-217518D01*
X535636Y-216060D01*
X537164Y-215185D01*
X538692D01*
X540221Y-215768D01*
X541531Y-217227D01*
G01X550516Y-232685D02*
Y-215185D01*
G01X558812D02*
X550516Y-225977D01*
G01X560122Y-232685D02*
X554227Y-221019D01*
G01X480952Y-170185D02*
Y-187685D01*
X489686D01*
G01X506749D02*
Y-176019D01*
G01Y-178060D02*
X505876Y-176894D01*
X504565Y-176310D01*
X503037Y-176019D01*
X501509Y-176602D01*
X500199Y-177768D01*
X499325Y-179518D01*
X498889Y-181852D01*
X499325Y-184185D01*
X500199Y-185935D01*
X501509Y-187102D01*
X503037Y-187685D01*
X504565Y-187393D01*
X505876Y-186519D01*
X506749Y-185352D01*
G01X515734Y-192935D02*
X517044Y-193518D01*
X518791Y-192935D01*
X519882Y-191769D01*
X520756Y-190310D01*
X522065Y-185644D01*
X524904Y-176019D01*
G01X517917D02*
X522065Y-185644D01*
G01X534544Y-179810D02*
X541531D01*
X540876Y-177768D01*
X539784Y-176602D01*
X538256Y-176019D01*
X536727Y-176310D01*
X535417Y-177185D01*
X534544Y-179227D01*
X534107Y-180977D01*
Y-182727D01*
X534544Y-184477D01*
X535636Y-186227D01*
X536946Y-187393D01*
X538474Y-187685D01*
X540002Y-187102D01*
X541531Y-185352D01*
G01X552262Y-187685D02*
Y-176019D01*
G01Y-178352D02*
X553354Y-177185D01*
X554446Y-176310D01*
X555974Y-176019D01*
X557065Y-176310D01*
X558376Y-177185D01*
G01X623066Y-187685D02*
Y-170185D01*
X627432D01*
X629179Y-171060D01*
X630489Y-172227D01*
X631581Y-173976D01*
X632454Y-176019D01*
X632672Y-178935D01*
X632454Y-181852D01*
X631581Y-183894D01*
X630489Y-185644D01*
X629179Y-186810D01*
X627432Y-187685D01*
X623066D01*
G01X642094Y-179810D02*
X649081D01*
X648426Y-177768D01*
X647334Y-176602D01*
X645806Y-176019D01*
X644277Y-176310D01*
X642967Y-177185D01*
X642094Y-179227D01*
X641657Y-180977D01*
Y-182727D01*
X642094Y-184477D01*
X643186Y-186227D01*
X644496Y-187393D01*
X646024Y-187685D01*
X647552Y-187102D01*
X649081Y-185352D01*
G01X659594Y-185644D02*
X660686Y-186810D01*
X662214Y-187685D01*
X663524D01*
X664834Y-187102D01*
X665707Y-186227D01*
X666144Y-185061D01*
X665926Y-183310D01*
X665052Y-182435D01*
X661122Y-180685D01*
X660249Y-178643D01*
X660686Y-177185D01*
X661559Y-176310D01*
X662869Y-176019D01*
X664179Y-176310D01*
X665489Y-177185D01*
G01X680369Y-176019D02*
Y-187685D01*
G01Y-171352D02*
X679932Y-171060D01*
Y-170477D01*
X680369Y-170185D01*
X680806Y-170477D01*
Y-171060D01*
X680369Y-171352D01*
G01X694812Y-192060D02*
X696341Y-193227D01*
X698087Y-193518D01*
X699615Y-193227D01*
X700926Y-191769D01*
X701799Y-189727D01*
Y-176019D01*
G01Y-178352D02*
X700926Y-177185D01*
X699615Y-176310D01*
X698087Y-176019D01*
X696341Y-176602D01*
X695249Y-177768D01*
X694375Y-179810D01*
X693939Y-181852D01*
X694157Y-183602D01*
X695031Y-185644D01*
X696341Y-187102D01*
X698087Y-187685D01*
X699397Y-187393D01*
X700926Y-186227D01*
X701799Y-185061D01*
G01X711657Y-187685D02*
Y-176019D01*
G01Y-178935D02*
X712531Y-177477D01*
X713841Y-176310D01*
X715587Y-176019D01*
X717115Y-176310D01*
X718426Y-177477D01*
X719081Y-179518D01*
Y-187685D01*
G01X729594Y-179810D02*
X736581D01*
X735926Y-177768D01*
X734834Y-176602D01*
X733306Y-176019D01*
X731777Y-176310D01*
X730467Y-177185D01*
X729594Y-179227D01*
X729157Y-180977D01*
Y-182727D01*
X729594Y-184477D01*
X730686Y-186227D01*
X731996Y-187393D01*
X733524Y-187685D01*
X735052Y-187102D01*
X736581Y-185352D01*
G01X747312Y-187685D02*
Y-176019D01*
G01Y-178352D02*
X748404Y-177185D01*
X749496Y-176310D01*
X751024Y-176019D01*
X752115Y-176310D01*
X753426Y-177185D01*
G01X664179Y-223935D02*
X668546D01*
Y-229185D01*
X667236Y-230935D01*
X665707Y-232102D01*
X663524Y-232685D01*
X661341Y-232102D01*
X659812Y-230935D01*
X658502Y-229185D01*
X657629Y-227143D01*
X657192Y-224810D01*
Y-222768D01*
X657629Y-221019D01*
X658502Y-218976D01*
X659812Y-217227D01*
X661122Y-216060D01*
X662869Y-215185D01*
X664397D01*
X666144Y-215768D01*
X667454Y-216935D01*
G01X684736Y-232685D02*
X676002D01*
Y-215185D01*
X684736D01*
G01X681242Y-223643D02*
X676002D01*
G01X693502Y-215185D02*
Y-232685D01*
X702236D01*
G01X715369D02*
X713622Y-232393D01*
X712094Y-231227D01*
X710784Y-229477D01*
X709910Y-227435D01*
X709474Y-225102D01*
Y-222768D01*
X709910Y-220435D01*
X710784Y-218393D01*
X712094Y-216644D01*
X713622Y-215477D01*
X715369Y-215185D01*
X717115Y-215477D01*
X718644Y-216644D01*
X719954Y-218393D01*
X720828Y-220435D01*
X721264Y-222768D01*
Y-225102D01*
X720828Y-227435D01*
X719954Y-229477D01*
X718644Y-231227D01*
X717115Y-232393D01*
X715369Y-232685D01*
G01X794069Y-215185D02*
X792322Y-215768D01*
X791012Y-217227D01*
X790139Y-218976D01*
X789484Y-221310D01*
X789266Y-223935D01*
X789484Y-226560D01*
X790139Y-228894D01*
X791012Y-230644D01*
X792322Y-232102D01*
X794069Y-232685D01*
X795815Y-232102D01*
X797126Y-230644D01*
X797999Y-228894D01*
X798654Y-226560D01*
X798872Y-223935D01*
X798654Y-221310D01*
X797999Y-218976D01*
X797126Y-217227D01*
X795815Y-215768D01*
X794069Y-215185D01*
G01X807421Y-225394D02*
X808949Y-223352D01*
X810259Y-222185D01*
X812006Y-221602D01*
X813534Y-222185D01*
X814626Y-223352D01*
X815499Y-225102D01*
X815717Y-227143D01*
X815499Y-228894D01*
X814626Y-230644D01*
X813315Y-232102D01*
X811787Y-232685D01*
X810041Y-232102D01*
X808512Y-230352D01*
X807639Y-227727D01*
X807421Y-224810D01*
X807857Y-221019D01*
X808512Y-218976D01*
X809604Y-216935D01*
X811132Y-215477D01*
X812661Y-215185D01*
X814189Y-215768D01*
X815281Y-217227D01*
G01X825139Y-233268D02*
X832999Y-215185D01*
G01X842421Y-218102D02*
X843731Y-216352D01*
X845259Y-215477D01*
X847006Y-215185D01*
X849189Y-215768D01*
X850717Y-217227D01*
X851154Y-218976D01*
X850936Y-220727D01*
X850062Y-222185D01*
X845696Y-225102D01*
X843731Y-227143D01*
X842421Y-230061D01*
X841984Y-232685D01*
X851154D01*
G01X859921Y-218102D02*
X861231Y-216352D01*
X862759Y-215477D01*
X864506Y-215185D01*
X866689Y-215768D01*
X868217Y-217227D01*
X868654Y-218976D01*
X868436Y-220727D01*
X867562Y-222185D01*
X863196Y-225102D01*
X861231Y-227143D01*
X859921Y-230061D01*
X859484Y-232685D01*
X868654D01*
G01X877639Y-233268D02*
X885499Y-215185D01*
G01X894921Y-218102D02*
X896231Y-216352D01*
X897759Y-215477D01*
X899506Y-215185D01*
X901689Y-215768D01*
X903217Y-217227D01*
X903654Y-218976D01*
X903436Y-220727D01*
X902562Y-222185D01*
X898196Y-225102D01*
X896231Y-227143D01*
X894921Y-230061D01*
X894484Y-232685D01*
X903654D01*
G01X916569Y-215185D02*
X914822Y-215768D01*
X913512Y-217227D01*
X912639Y-218976D01*
X911984Y-221310D01*
X911766Y-223935D01*
X911984Y-226560D01*
X912639Y-228894D01*
X913512Y-230644D01*
X914822Y-232102D01*
X916569Y-232685D01*
X918315Y-232102D01*
X919626Y-230644D01*
X920499Y-228894D01*
X921154Y-226560D01*
X921372Y-223935D01*
X921154Y-221310D01*
X920499Y-218976D01*
X919626Y-217227D01*
X918315Y-215768D01*
X916569Y-215185D01*
G01X934069Y-232685D02*
Y-215185D01*
X931449Y-218685D01*
G01Y-232685D02*
X936689D01*
G01X951132D02*
X951569Y-228894D01*
X952224Y-225685D01*
X953097Y-222768D01*
X954189Y-219560D01*
X955936Y-215185D01*
X947202D01*
G01X841766Y-187685D02*
Y-170185D01*
X846132D01*
X847879Y-171060D01*
X849189Y-172227D01*
X850281Y-173976D01*
X851154Y-176019D01*
X851372Y-178935D01*
X851154Y-181852D01*
X850281Y-183894D01*
X849189Y-185644D01*
X847879Y-186810D01*
X846132Y-187685D01*
X841766D01*
G01X867999D02*
Y-176019D01*
G01Y-178060D02*
X867126Y-176894D01*
X865815Y-176310D01*
X864287Y-176019D01*
X862759Y-176602D01*
X861449Y-177768D01*
X860575Y-179518D01*
X860139Y-181852D01*
X860575Y-184185D01*
X861449Y-185935D01*
X862759Y-187102D01*
X864287Y-187685D01*
X865815Y-187393D01*
X867126Y-186519D01*
X867999Y-185352D01*
G01X881569Y-170185D02*
Y-187685D01*
G01X878512Y-176019D02*
X884626D01*
G01X895794Y-179810D02*
X902781D01*
X902126Y-177768D01*
X901034Y-176602D01*
X899506Y-176019D01*
X897977Y-176310D01*
X896667Y-177185D01*
X895794Y-179227D01*
X895357Y-180977D01*
Y-182727D01*
X895794Y-184477D01*
X896886Y-186227D01*
X898196Y-187393D01*
X899724Y-187685D01*
X901252Y-187102D01*
X902781Y-185352D01*
G54D24*
X207500Y74700D03*
X211100Y32000D03*
X320946Y42829D03*
X324423Y42824D03*
X479900Y223700D03*
X502868Y159486D03*
G54D33*
X313300Y32000D03*
X305300D03*
X317800Y142000D03*
X305800Y133500D03*
X336300Y20000D03*
X325300Y142000D03*
X348800Y29500D03*
X356800D03*
G54D15*
X68112Y15039D03*
Y59528D03*
X233462Y15039D03*
Y59528D03*
X359156Y142992D03*
Y208740D03*
X524506Y142992D03*
Y208740D03*
G54D25*
X207500Y78300D03*
X211100Y35600D03*
X320946Y46429D03*
X324423Y46424D03*
X479900Y227300D03*
X502868Y163086D03*
G54D34*
X312657Y66142D03*
Y107716D03*
G54D16*
X93287Y10039D03*
X88287D03*
X93287Y54528D03*
X88287D03*
X118287Y10039D03*
X113287D03*
X108287D03*
X103287D03*
X98287D03*
X118287Y54528D03*
X113287D03*
X108287D03*
X103287D03*
X98287D03*
X163287Y10039D03*
X158287D03*
X153287D03*
X148287D03*
X143287D03*
X163287Y54528D03*
X158287D03*
X153287D03*
X148287D03*
X143287D03*
X183287Y10039D03*
X178287D03*
X173287D03*
X168287D03*
X183287Y54528D03*
X178287D03*
X173287D03*
X168287D03*
X208287Y10039D03*
X203287D03*
X198287D03*
X193287D03*
X188287D03*
X208287Y54528D03*
X203287D03*
X198287D03*
X193287D03*
X188287D03*
X213287Y10039D03*
Y54528D03*
X389331Y137992D03*
X384331D03*
X379331D03*
X389331Y203740D03*
X384331D03*
X379331D03*
X409331Y137992D03*
X404331D03*
X399331D03*
X394331D03*
X409331Y203740D03*
X404331D03*
X399331D03*
X394331D03*
X434331Y137992D03*
Y203740D03*
X459331Y137992D03*
X454331D03*
X449331D03*
X444331D03*
X439331D03*
X459331Y203740D03*
X454331D03*
X449331D03*
X444331D03*
X439331D03*
X479331Y137992D03*
X474331D03*
X469331D03*
X464331D03*
X479331Y203740D03*
X474331D03*
X469331D03*
X464331D03*
X504331Y137992D03*
X499331D03*
X494331D03*
X489331D03*
X484331D03*
X504331Y203740D03*
X499331D03*
X494331D03*
X489331D03*
X484331D03*
G54D35*
X327151Y153540D03*
X357000Y41200D03*
G54D26*
X225097Y15039D03*
Y59528D03*
X516141Y142992D03*
Y208740D03*
G54D17*
X75100Y36700D03*
X74635Y29153D03*
X506868Y166599D03*
G54D27*
X214956Y32099D03*
X211500Y74800D03*
X320965Y32100D03*
X325152Y32095D03*
X483700Y223800D03*
X506868Y159586D03*
G54D18*
X140237Y23464D03*
X137087D03*
X133937D03*
X130787D03*
X127637D03*
X124487D03*
X121337D03*
X140237Y67953D03*
X137087D03*
X133937D03*
X130787D03*
X127637D03*
X124487D03*
X121337D03*
X412381Y151417D03*
Y217165D03*
X431281Y151417D03*
X428131D03*
X424981D03*
X421831D03*
X418681D03*
X415531D03*
X431281Y217165D03*
X428131D03*
X424981D03*
X421831D03*
X418681D03*
X415531D03*
G54D36*
X327151Y150140D03*
X357000Y37800D03*
G54D28*
X214956Y35499D03*
X211500Y78200D03*
X320965Y35500D03*
X325152Y35495D03*
X483700Y227200D03*
X506868Y162986D03*
G54D19*
X182700Y75000D03*
X186900Y32100D03*
X220920Y33897D03*
X216594Y74962D03*
X464035Y224263D03*
X488700Y158300D03*
X491846Y224052D03*
X511700Y158500D03*
G54D37*
X331151Y153640D03*
X361000Y41300D03*
G54D29*
X228630Y76864D03*
Y85564D03*
X244456Y33299D03*
X233456D03*
X244456Y41999D03*
X233456D03*
X239630Y76864D03*
Y85564D03*
X289800Y150000D03*
X300800D03*
X289800Y158700D03*
X300800D03*
G54D38*
X331151Y150040D03*
X361000Y37700D03*
G54D39*
X473149Y79094D03*
X532205D03*
M02*
